# SCM (Grand Teton) — schematic netlist excerpt (pin names and nets, part order shuffled) for the footprints in the layout excerpt that follows; sources: Cadence DE-HDL packaged netlist, KiCad conversion of 12092022_DA0F0TMDCD0_F0T_Management_Board_D_brd_V3_OCP.brd

R190  Q_RES  1K 1% CHIP  pkg 0402LF  page 14 : A = P1V2_P1V0_I3C_VDDL1 ; B = I3C2_SPD_SCL
R92  Q_RES  2.2K 5% CHIP  pkg 0402LF  page 23 : A = CRT_VCC5 ; B = V_BMC_LS_DDC_SCL

(kicad_pcb
	(version 20260206)
	(generator "pcbnew")
	(generator_version "10.0")
	(general
		(thickness 1.6)
		(legacy_teardrops no)
	)
	(paper "A4")
	(title_block
		(title "12092022_DA0F0TMDCD0_F0T_Management_Board_D_brd_V3_OCP.brd")
		(comment 1 "Grand Teton / footprints 1139-1140 of 1440")
	)
	(layers
		(0 "F.Cu" signal "TOP")
		(4 "In1.Cu" signal "GND")
		(6 "In2.Cu" signal "IN1")
		(8 "In3.Cu" signal "GND1")
		(10 "In4.Cu" signal "IN2")
		(12 "In5.Cu" signal "VCC")
		(14 "In6.Cu" signal "VCC1")
		(16 "In7.Cu" signal "IN3")
		(18 "In8.Cu" signal "GND2")
		(20 "In9.Cu" signal "IN4")
		(22 "In10.Cu" signal "GND3")
		(2 "B.Cu" signal "BOTTOM")
		(9 "F.Adhes" user "F.Adhesive")
		(11 "B.Adhes" user "B.Adhesive")
		(13 "F.Paste" user "Package Geometry/Pastemask Top")
		(15 "B.Paste" user "Package Geometry/Pastemask Bottom")
		(5 "F.SilkS" user "Ref Des/Silkscreen Top")
		(7 "B.SilkS" user "Ref Des/Silkscreen Bottom")
		(1 "F.Mask" user "Board Geometry/Soldermask Top")
		(3 "B.Mask" user "Board Geometry/Soldermask Bottom")
		(17 "Dwgs.User" user "User.Drawings")
		(19 "Cmts.User" user "User.Comments")
		(21 "Eco1.User" user "User.Eco1")
		(23 "Eco2.User" user "User.Eco2")
		(25 "Edge.Cuts" user "Board Geometry/Outline")
		(27 "Margin" user)
		(31 "F.CrtYd" user "Package Geometry/Place Bound Top")
		(29 "B.CrtYd" user "Package Geometry/Place Bound Bottom")
		(35 "F.Fab" user "Ref Des/Assembly Top")
		(33 "B.Fab" user "Ref Des/Assembly Bottom")
	)
	(footprint ""
		(layer "B.Cu")
		(at 44.193968 -65.743074 -90)
		(property "Reference" "R190"
			(at 0 0 90)
			(layer "B.SilkS")
			(hide yes)
			(effects
				(font
					(size 1.27 1.27)
				)
				(justify mirror)
			)
		)
		(property "Value" ""
			(at 0 0 90)
			(layer "B.Fab")
			(effects
				(font
					(size 1.27 1.27)
				)
				(justify mirror)
			)
		)
		(duplicate_pad_numbers_are_jumpers no)
		(fp_line
			(start -0.7874 0.4064)
			(end 0.7874 0.4064)
			(stroke
				(width 0.1524)
				(type default)
			)
			(layer "B.SilkS")
		)
		(fp_line
			(start 0.7874 0.4064)
			(end 0.7874 -0.4064)
			(stroke
				(width 0.1524)
				(type default)
			)
			(layer "B.SilkS")
		)
		(fp_line
			(start -0.7874 -0.4064)
			(end -0.7874 0.4064)
			(stroke
				(width 0.1524)
				(type default)
			)
			(layer "B.SilkS")
		)
		(fp_line
			(start 0.7874 -0.4064)
			(end -0.7874 -0.4064)
			(stroke
				(width 0.1524)
				(type default)
			)
			(layer "B.SilkS")
		)
		(fp_line
			(start -0.67945 0.3048)
			(end -0.120396 0.3048)
			(stroke
				(width 0.1)
				(type default)
			)
			(layer "B.Fab")
		)
		(fp_line
			(start -0.120396 0.3048)
			(end -0.120396 0.2794)
			(stroke
				(width 0.1)
				(type default)
			)
			(layer "B.Fab")
		)
		(fp_line
			(start 0.12065 0.3048)
			(end 0.67945 0.3048)
			(stroke
				(width 0.1)
				(type default)
			)
			(layer "B.Fab")
		)
		(fp_line
			(start 0.67945 0.3048)
			(end 0.67945 -0.305054)
			(stroke
				(width 0.1)
				(type default)
			)
			(layer "B.Fab")
		)
		(fp_line
			(start -0.120396 0.2794)
			(end 0.12065 0.2794)
			(stroke
				(width 0.1)
				(type default)
			)
			(layer "B.Fab")
		)
		(fp_line
			(start 0.12065 0.2794)
			(end 0.12065 0.3048)
			(stroke
				(width 0.1)
				(type default)
			)
			(layer "B.Fab")
		)
		(fp_line
			(start -0.12065 -0.2794)
			(end -0.12065 -0.3048)
			(stroke
				(width 0.1)
				(type default)
			)
			(layer "B.Fab")
		)
		(fp_line
			(start 0.12065 -0.2794)
			(end -0.12065 -0.2794)
			(stroke
				(width 0.1)
				(type default)
			)
			(layer "B.Fab")
		)
		(fp_line
			(start -0.67945 -0.3048)
			(end -0.67945 0.3048)
			(stroke
				(width 0.1)
				(type default)
			)
			(layer "B.Fab")
		)
		(fp_line
			(start -0.12065 -0.3048)
			(end -0.67945 -0.3048)
			(stroke
				(width 0.1)
				(type default)
			)
			(layer "B.Fab")
		)
		(fp_line
			(start 0.12065 -0.305054)
			(end 0.12065 -0.2794)
			(stroke
				(width 0.1)
				(type default)
			)
			(layer "B.Fab")
		)
		(fp_line
			(start 0.67945 -0.305054)
			(end 0.12065 -0.305054)
			(stroke
				(width 0.1)
				(type default)
			)
			(layer "B.Fab")
		)
		(pad "1" smd circle
			(at 0.40005 0 90)
			(size 0 0)
			(layers "B.Cu" "B.Mask" "B.Paste")
			(net "P1V2_P1V0_I3C_VDDL1")
		)
		(pad "2" smd circle
			(at -0.40005 0 90)
			(size 0 0)
			(layers "B.Cu" "B.Mask" "B.Paste")
			(net "I3C2_SPD_SCL")
		)
	)
	(footprint ""
		(layer "B.Cu")
		(at 34.0106 -21.4122)
		(property "Reference" "R92"
			(at 0 0 0)
			(layer "B.SilkS")
			(hide yes)
			(effects
				(font
					(size 1.27 1.27)
				)
				(justify mirror)
			)
		)
		(property "Value" ""
			(at 0 0 0)
			(layer "B.Fab")
			(effects
				(font
					(size 1.27 1.27)
				)
				(justify mirror)
			)
		)
		(duplicate_pad_numbers_are_jumpers no)
		(fp_line
			(start -0.7874 -0.4064)
			(end -0.7874 0.4064)
			(stroke
				(width 0.1524)
				(type default)
			)
			(layer "B.SilkS")
		)
		(fp_line
			(start -0.7874 0.4064)
			(end 0.7874 0.4064)
			(stroke
				(width 0.1524)
				(type default)
			)
			(layer "B.SilkS")
		)
		(fp_line
			(start 0.7874 -0.4064)
			(end -0.7874 -0.4064)
			(stroke
				(width 0.1524)
				(type default)
			)
			(layer "B.SilkS")
		)
		(fp_line
			(start 0.7874 0.4064)
			(end 0.7874 -0.4064)
			(stroke
				(width 0.1524)
				(type default)
			)
			(layer "B.SilkS")
		)
		(fp_line
			(start -0.67945 -0.3048)
			(end -0.67945 0.3048)
			(stroke
				(width 0.1)
				(type default)
			)
			(layer "B.Fab")
		)
		(fp_line
			(start -0.67945 0.3048)
			(end -0.120396 0.3048)
			(stroke
				(width 0.1)
				(type default)
			)
			(layer "B.Fab")
		)
		(fp_line
			(start -0.12065 -0.3048)
			(end -0.67945 -0.3048)
			(stroke
				(width 0.1)
				(type default)
			)
			(layer "B.Fab")
		)
		(fp_line
			(start -0.12065 -0.2794)
			(end -0.12065 -0.3048)
			(stroke
				(width 0.1)
				(type default)
			)
			(layer "B.Fab")
		)
		(fp_line
			(start -0.120396 0.2794)
			(end 0.12065 0.2794)
			(stroke
				(width 0.1)
				(type default)
			)
			(layer "B.Fab")
		)
		(fp_line
			(start -0.120396 0.3048)
			(end -0.120396 0.2794)
			(stroke
				(width 0.1)
				(type default)
			)
			(layer "B.Fab")
		)
		(fp_line
			(start 0.12065 -0.305054)
			(end 0.12065 -0.2794)
			(stroke
				(width 0.1)
				(type default)
			)
			(layer "B.Fab")
		)
		(fp_line
			(start 0.12065 -0.2794)
			(end -0.12065 -0.2794)
			(stroke
				(width 0.1)
				(type default)
			)
			(layer "B.Fab")
		)
		(fp_line
			(start 0.12065 0.2794)
			(end 0.12065 0.3048)
			(stroke
				(width 0.1)
				(type default)
			)
			(layer "B.Fab")
		)
		(fp_line
			(start 0.12065 0.3048)
			(end 0.67945 0.3048)
			(stroke
				(width 0.1)
				(type default)
			)
			(layer "B.Fab")
		)
		(fp_line
			(start 0.67945 -0.305054)
			(end 0.12065 -0.305054)
			(stroke
				(width 0.1)
				(type default)
			)
			(layer "B.Fab")
		)
		(fp_line
			(start 0.67945 0.3048)
			(end 0.67945 -0.305054)
			(stroke
				(width 0.1)
				(type default)
			)
			(layer "B.Fab")
		)
		(pad "1" smd circle
			(at 0.40005 0 180)
			(size 0 0)
			(layers "B.Cu" "B.Mask" "B.Paste")
			(net "CRT_VCC5")
		)
		(pad "2" smd circle
			(at -0.40005 0 180)
			(size 0 0)
			(layers "B.Cu" "B.Mask" "B.Paste")
			(net "V_BMC_LS_DDC_SCL")
		)
	)
)
